(kicad_pcb
	(version 20260206)
	(generator "pcbnew")
	(generator_version "10.0")
	(general
		(thickness 1.6)
		(legacy_teardrops no)
	)
	(paper "A4")
	(title_block
		(title "Bryce Canyon_R.DPB_16317-1_OCP.brd")
		(comment 1 "Bryce Canyon / footprints 898-904 of 2099")
	)
	(layers
		(0 "F.Cu" signal "TOP")
		(4 "In1.Cu" signal "L2GND")
		(6 "In2.Cu" signal "L3")
		(8 "In3.Cu" signal "L4VCC")
		(10 "In4.Cu" signal "L5VCC")
		(12 "In5.Cu" signal "L6")
		(14 "In6.Cu" signal "L7GND")
		(2 "B.Cu" signal "BOTTOM")
		(9 "F.Adhes" user "F.Adhesive")
		(11 "B.Adhes" user "B.Adhesive")
		(13 "F.Paste" user "Package Geometry/Pastemask Top")
		(15 "B.Paste" user "Package Geometry/Pastemask Bottom")
		(5 "F.SilkS" user "Ref Des/Silkscreen Top")
		(7 "B.SilkS" user "Ref Des/Silkscreen Bottom")
		(1 "F.Mask" user "Board Geometry/Soldermask Top")
		(3 "B.Mask" user "Board Geometry/Soldermask Bottom")
		(17 "Dwgs.User" user "User.Drawings")
		(19 "Cmts.User" user "User.Comments")
		(21 "Eco1.User" user "User.Eco1")
		(23 "Eco2.User" user "User.Eco2")
		(25 "Edge.Cuts" user "Board Geometry/Outline")
		(27 "Margin" user)
		(31 "F.CrtYd" user "Package Geometry/Place Bound Top")
		(29 "B.CrtYd" user "Package Geometry/Place Bound Bottom")
		(35 "F.Fab" user "Ref Des/Assembly Top")
		(33 "B.Fab" user "Ref Des/Assembly Bottom")
	)
	(footprint ""
		(layer "F.Cu")
		(at 174.498 -254.127 -90)
		(property "Reference" "C103"
			(at 0 0 270)
			(layer "F.SilkS")
			(hide yes)
			(effects
				(font
					(size 1.27 1.27)
				)
			)
		)
		(property "Value" "SCD033U25V2KX-GP"
			(at 1.1811 -2.7051 270)
			(unlocked yes)
			(layer "F.Fab")
			(hide yes)
			(effects
				(font
					(size 1.016 1.016)
					(thickness 0.1524)
				)
			)
		)
		(property "Device Type" "C402H22"
			(at 1.1811 -4.2291 270)
			(unlocked yes)
			(layer "F.Fab")
			(hide yes)
			(effects
				(font
					(size 1.016 1.016)
					(thickness 0.1524)
				)
			)
		)
		(duplicate_pad_numbers_are_jumpers no)
		(fp_rect
			(start -0.4318 0.9525)
			(end 0.4318 -0.9525)
			(stroke
				(width 0)
				(type default)
			)
			(fill no)
			(layer "F.CrtYd")
		)
		(fp_rect
			(start -0.4318 0.9525)
			(end 0.4318 -0.9525)
			(stroke
				(width 0)
				(type default)
			)
			(fill no)
			(layer "F.Fab")
		)
		(pad "1" smd custom
			(at 0 -0.4445 270)
			(size 0.1524 0.1524)
			(layers "F.Cu" "F.Mask" "F.Paste")
			(net "SW_HDD_P5")
			(options
				(clearance outline)
				(anchor circle)
			)
			(primitives
				(gr_poly
					(pts
						(arc
							(start 0.3048 -0.2032)
							(mid 0.275042 -0.275042)
							(end 0.2032 -0.3048)
						)
						(arc
							(start -0.2032 -0.3048)
							(mid -0.275042 -0.275042)
							(end -0.3048 -0.2032)
						)
						(arc
							(start -0.3048 0.2032)
							(mid -0.275042 0.275042)
							(end -0.2032 0.3048)
						)
						(arc
							(start 0.2032 0.3048)
							(mid 0.275042 0.275042)
							(end 0.3048 0.2032)
						)
					)
					(width 0)
					(fill yes)
				)
			)
		)
		(pad "2" smd custom
			(at 0 0.4445 270)
			(size 0.1524 0.1524)
			(layers "F.Cu" "F.Mask" "F.Paste")
			(net "GND")
			(options
				(clearance outline)
				(anchor circle)
			)
			(primitives
				(gr_poly
					(pts
						(arc
							(start 0.3048 -0.2032)
							(mid 0.275042 -0.275042)
							(end 0.2032 -0.3048)
						)
						(arc
							(start -0.2032 -0.3048)
							(mid -0.275042 -0.275042)
							(end -0.3048 -0.2032)
						)
						(arc
							(start -0.3048 0.2032)
							(mid -0.275042 0.275042)
							(end -0.2032 0.3048)
						)
						(arc
							(start 0.2032 0.3048)
							(mid 0.275042 0.275042)
							(end 0.3048 0.2032)
						)
					)
					(width 0)
					(fill yes)
				)
			)
		)
	)
	(footprint ""
		(layer "F.Cu")
		(at 396.367 -243.586 180)
		(property "Reference" "R292"
			(at 0 0 180)
			(layer "F.SilkS")
			(hide yes)
			(effects
				(font
					(size 1.27 1.27)
				)
			)
		)
		(property "Value" "1KR2F-3-GP"
			(at 0.064008 -3.993896 180)
			(unlocked yes)
			(layer "F.Fab")
			(hide yes)
			(effects
				(font
					(size 1.016 1.016)
					(thickness 0.1524)
				)
			)
		)
		(property "Device Type" "R402H16"
			(at 0.064008 -5.517896 180)
			(unlocked yes)
			(layer "F.Fab")
			(hide yes)
			(effects
				(font
					(size 1.016 1.016)
					(thickness 0.1524)
				)
			)
		)
		(duplicate_pad_numbers_are_jumpers no)
		(fp_line
			(start 0.508 -0.9398)
			(end -0.508 -0.9398)
			(stroke
				(width 0.1524)
				(type default)
			)
			(layer "F.SilkS")
		)
		(fp_line
			(start -0.508 -0.9398)
			(end -0.508 0.9398)
			(stroke
				(width 0.1524)
				(type default)
			)
			(layer "F.SilkS")
		)
		(fp_rect
			(start -0.508 0.9398)
			(end 0.508 -0.9398)
			(stroke
				(width 0)
				(type default)
			)
			(fill no)
			(layer "F.CrtYd")
		)
		(fp_rect
			(start -0.508 0.9398)
			(end 0.508 -0.9398)
			(stroke
				(width 0)
				(type default)
			)
			(fill no)
			(layer "F.Fab")
		)
		(pad "1" smd custom
			(at 0 -0.4445 180)
			(size 0.1397 0.1397)
			(layers "F.Cu" "F.Mask" "F.Paste")
			(net "P3V3_STBY_B")
			(options
				(clearance outline)
				(anchor circle)
			)
			(primitives
				(gr_poly
					(pts
						(arc
							(start -0.1778 -0.2794)
							(mid -0.249642 -0.249642)
							(end -0.2794 -0.1778)
						)
						(arc
							(start -0.2794 0.1778)
							(mid -0.249642 0.249642)
							(end -0.1778 0.2794)
						)
						(arc
							(start 0.1778 0.2794)
							(mid 0.249642 0.249642)
							(end 0.2794 0.1778)
						)
						(arc
							(start 0.2794 -0.1778)
							(mid 0.249642 -0.249642)
							(end 0.1778 -0.2794)
						)
					)
					(width 0)
					(fill yes)
				)
			)
		)
		(pad "2" smd custom
			(at 0 0.4445 180)
			(size 0.1397 0.1397)
			(layers "F.Cu" "F.Mask" "F.Paste")
			(net "SW_PWR_R_HDD8")
			(options
				(clearance outline)
				(anchor circle)
			)
			(primitives
				(gr_poly
					(pts
						(arc
							(start -0.1778 -0.2794)
							(mid -0.249642 -0.249642)
							(end -0.2794 -0.1778)
						)
						(arc
							(start -0.2794 0.1778)
							(mid -0.249642 0.249642)
							(end -0.1778 0.2794)
						)
						(arc
							(start 0.1778 0.2794)
							(mid 0.249642 0.249642)
							(end 0.2794 0.1778)
						)
						(arc
							(start 0.2794 -0.1778)
							(mid 0.249642 -0.249642)
							(end 0.1778 -0.2794)
						)
					)
					(width 0)
					(fill yes)
				)
			)
		)
	)
	(footprint ""
		(layer "F.Cu")
		(at 456.674982 -293.799768)
		(property "Reference" ""
			(at 0 0 0)
			(layer "F.SilkS")
			(hide yes)
			(effects
				(font
					(size 1.27 1.27)
				)
			)
		)
		(property "Value" "*"
			(at -8.398764 -8.057642 0)
			(unlocked yes)
			(layer "F.Fab")
			(hide yes)
			(effects
				(font
					(size 1.016 1.016)
					(thickness 0.1524)
				)
			)
		)
		(duplicate_pad_numbers_are_jumpers no)
		(fp_poly
			(pts
				(arc
					(start 7.3152 0)
					(mid 0 7.3152)
					(end -7.3152 0)
				)
				(arc
					(start -7.3152 -5.9944)
					(mid 0 -13.3096)
					(end 7.3152 -5.9944)
				)
			)
			(stroke
				(width 0)
				(type default)
			)
			(fill no)
			(layer "B.CrtYd")
		)
		(fp_poly
			(pts
				(arc
					(start 7.3152 0)
					(mid 0 7.3152)
					(end -7.3152 0)
				)
				(arc
					(start -7.3152 -5.9944)
					(mid 0 -13.3096)
					(end 7.3152 -5.9944)
				)
			)
			(stroke
				(width 0)
				(type default)
			)
			(fill no)
			(layer "F.CrtYd")
		)
		(fp_poly
			(pts
				(arc
					(start 7.3152 0)
					(mid 0 7.3152)
					(end -7.3152 0)
				)
				(arc
					(start -7.3152 -5.9944)
					(mid 0 -13.3096)
					(end 7.3152 -5.9944)
				)
			)
			(stroke
				(width 0)
				(type default)
			)
			(fill no)
			(layer "B.Fab")
		)
		(fp_poly
			(pts
				(arc
					(start 7.3152 0)
					(mid 0 7.3152)
					(end -7.3152 0)
				)
				(arc
					(start -7.3152 -5.9944)
					(mid 0 -13.3096)
					(end 7.3152 -5.9944)
				)
			)
			(stroke
				(width 0)
				(type default)
			)
			(fill no)
			(layer "F.Fab")
		)
		(pad "1" thru_hole oval
			(at 0 0)
			(size 14.0208 20.0152)
			(drill 0.0254
				(offset 0 -2.9972)
			)
			(layers "*.Cu" "*.Mask")
			(remove_unused_layers no)
			(net "Net_13")
			(clearance -1.002284)
			(thermal_gap 0.1524)
			(padstack
				(mode front_inner_back)
				(layer "Inner"
					(shape custom)
					(size 2.928012 2.928012)
					(options
						(anchor circle)
					)
					(primitives
						(gr_poly
							(pts
								(arc
									(start 4.571746 -2.084324)
									(mid 0.000333 7.430372)
									(end -4.571492 -2.084324)
								)
								(arc
									(start -4.571492 -2.084324)
									(mid -3.570296 -3.611977)
									(end -2.875026 -5.30098)
								)
								(arc
									(start -2.875026 -5.30098)
									(mid 0.000217 -7.43089)
									(end 2.87528 -5.30098)
								)
								(arc
									(start 2.87528 -5.30098)
									(mid 3.570511 -3.611956)
									(end 4.571746 -2.084324)
								)
							)
							(width 0)
							(fill yes)
						)
					)
					(clearance 0.1524)
				)
				(layer "B.Cu"
					(shape oval)
					(size 14.0208 20.0152)
					(offset 0 -2.9972)
					(clearance -1.002284)
				)
			)
		)
		(zone
			(layers "F.Cu" "B.Cu" "In1.Cu" "In2.Cu" "In3.Cu" "In4.Cu" "In5.Cu" "In6.Cu")
			(hatch none 0.5)
			(connect_pads
				(clearance 0)
			)
			(min_thickness 0.25)
			(keepout
				(tracks not_allowed)
				(vias allowed)
				(pads allowed)
				(copperpour not_allowed)
				(footprints allowed)
			)
			(placement
				(enabled no)
				(sheetname "")
			)
			(fill
				(thermal_gap 0.5)
				(thermal_bridge_width 0.5)
				(island_removal_mode 0)
			)
			(polygon
				(pts
					(arc
						(start 449.664582 -299.794168)
						(mid 456.674982 -306.804568)
						(end 463.685382 -299.794168)
					)
					(arc
						(start 463.685382 -293.799768)
						(mid 456.674982 -286.789368)
						(end 449.664582 -293.799768)
					)
				)
			)
		)
	)
	(footprint ""
		(layer "F.Cu")
		(at 113.03 -131.572)
		(property "Reference" "R432"
			(at 0 0 0)
			(layer "F.SilkS")
			(hide yes)
			(effects
				(font
					(size 1.27 1.27)
				)
			)
		)
		(property "Value" "0R2J-2-GP"
			(at 0.064008 -3.993896 0)
			(unlocked yes)
			(layer "F.Fab")
			(hide yes)
			(effects
				(font
					(size 1.016 1.016)
					(thickness 0.1524)
				)
			)
		)
		(property "Device Type" "R402H16"
			(at 0.064008 -5.517896 0)
			(unlocked yes)
			(layer "F.Fab")
			(hide yes)
			(effects
				(font
					(size 1.016 1.016)
					(thickness 0.1524)
				)
			)
		)
		(duplicate_pad_numbers_are_jumpers no)
		(fp_line
			(start -0.508 -0.9398)
			(end -0.508 0.9398)
			(stroke
				(width 0.1524)
				(type default)
			)
			(layer "F.SilkS")
		)
		(fp_line
			(start 0.508 -0.9398)
			(end -0.508 -0.9398)
			(stroke
				(width 0.1524)
				(type default)
			)
			(layer "F.SilkS")
		)
		(fp_rect
			(start -0.508 0.9398)
			(end 0.508 -0.9398)
			(stroke
				(width 0)
				(type default)
			)
			(fill no)
			(layer "F.CrtYd")
		)
		(fp_rect
			(start -0.508 0.9398)
			(end 0.508 -0.9398)
			(stroke
				(width 0)
				(type default)
			)
			(fill no)
			(layer "F.Fab")
		)
		(pad "1" smd custom
			(at 0 -0.4445)
			(size 0.1397 0.1397)
			(layers "F.Cu" "F.Mask" "F.Paste")
			(net "SW_HDD_G15")
			(options
				(clearance outline)
				(anchor circle)
			)
			(primitives
				(gr_poly
					(pts
						(arc
							(start -0.1778 -0.2794)
							(mid -0.249642 -0.249642)
							(end -0.2794 -0.1778)
						)
						(arc
							(start -0.2794 0.1778)
							(mid -0.249642 0.249642)
							(end -0.1778 0.2794)
						)
						(arc
							(start 0.1778 0.2794)
							(mid 0.249642 0.249642)
							(end 0.2794 0.1778)
						)
						(arc
							(start 0.2794 -0.1778)
							(mid 0.249642 -0.249642)
							(end 0.1778 -0.2794)
						)
					)
					(width 0)
					(fill yes)
				)
			)
		)
		(pad "2" smd custom
			(at 0 0.4445)
			(size 0.1397 0.1397)
			(layers "F.Cu" "F.Mask" "F.Paste")
			(net "SW_HDD_R15")
			(options
				(clearance outline)
				(anchor circle)
			)
			(primitives
				(gr_poly
					(pts
						(arc
							(start -0.1778 -0.2794)
							(mid -0.249642 -0.249642)
							(end -0.2794 -0.1778)
						)
						(arc
							(start -0.2794 0.1778)
							(mid -0.249642 0.249642)
							(end -0.1778 0.2794)
						)
						(arc
							(start 0.1778 0.2794)
							(mid 0.249642 0.249642)
							(end 0.2794 0.1778)
						)
						(arc
							(start 0.2794 -0.1778)
							(mid 0.249642 -0.249642)
							(end 0.1778 -0.2794)
						)
					)
					(width 0)
					(fill yes)
				)
			)
		)
	)
	(footprint ""
		(layer "F.Cu")
		(at 48.387 -254.127 -90)
		(property "Reference" "C51"
			(at 0 0 270)
			(layer "F.SilkS")
			(hide yes)
			(effects
				(font
					(size 1.27 1.27)
				)
			)
		)
		(property "Value" "SCD033U25V2KX-GP"
			(at 1.1811 -2.7051 270)
			(unlocked yes)
			(layer "F.Fab")
			(hide yes)
			(effects
				(font
					(size 1.016 1.016)
					(thickness 0.1524)
				)
			)
		)
		(property "Device Type" "C402H22"
			(at 1.1811 -4.2291 270)
			(unlocked yes)
			(layer "F.Fab")
			(hide yes)
			(effects
				(font
					(size 1.016 1.016)
					(thickness 0.1524)
				)
			)
		)
		(duplicate_pad_numbers_are_jumpers no)
		(fp_rect
			(start -0.4318 0.9525)
			(end 0.4318 -0.9525)
			(stroke
				(width 0)
				(type default)
			)
			(fill no)
			(layer "F.CrtYd")
		)
		(fp_rect
			(start -0.4318 0.9525)
			(end 0.4318 -0.9525)
			(stroke
				(width 0)
				(type default)
			)
			(fill no)
			(layer "F.Fab")
		)
		(pad "1" smd custom
			(at 0 -0.4445 270)
			(size 0.1524 0.1524)
			(layers "F.Cu" "F.Mask" "F.Paste")
			(net "SW_HDD_P1")
			(options
				(clearance outline)
				(anchor circle)
			)
			(primitives
				(gr_poly
					(pts
						(arc
							(start 0.3048 -0.2032)
							(mid 0.275042 -0.275042)
							(end 0.2032 -0.3048)
						)
						(arc
							(start -0.2032 -0.3048)
							(mid -0.275042 -0.275042)
							(end -0.3048 -0.2032)
						)
						(arc
							(start -0.3048 0.2032)
							(mid -0.275042 0.275042)
							(end -0.2032 0.3048)
						)
						(arc
							(start 0.2032 0.3048)
							(mid 0.275042 0.275042)
							(end 0.3048 0.2032)
						)
					)
					(width 0)
					(fill yes)
				)
			)
		)
		(pad "2" smd custom
			(at 0 0.4445 270)
			(size 0.1524 0.1524)
			(layers "F.Cu" "F.Mask" "F.Paste")
			(net "GND")
			(options
				(clearance outline)
				(anchor circle)
			)
			(primitives
				(gr_poly
					(pts
						(arc
							(start 0.3048 -0.2032)
							(mid 0.275042 -0.275042)
							(end 0.2032 -0.3048)
						)
						(arc
							(start -0.2032 -0.3048)
							(mid -0.275042 -0.275042)
							(end -0.3048 -0.2032)
						)
						(arc
							(start -0.3048 0.2032)
							(mid -0.275042 0.275042)
							(end -0.2032 0.3048)
						)
						(arc
							(start 0.2032 0.3048)
							(mid 0.275042 0.275042)
							(end 0.3048 0.2032)
						)
					)
					(width 0)
					(fill yes)
				)
			)
		)
	)
	(footprint ""
		(layer "F.Cu")
		(at 460.5274 -6.2992 -90)
		(property "Reference" "C32"
			(at 0 0 270)
			(layer "F.SilkS")
			(hide yes)
			(effects
				(font
					(size 1.27 1.27)
				)
			)
		)
		(property "Value" "SCD1U16V2KX-3GP"
			(at 1.1811 -2.7051 270)
			(unlocked yes)
			(layer "F.Fab")
			(hide yes)
			(effects
				(font
					(size 1.016 1.016)
					(thickness 0.1524)
				)
			)
		)
		(property "Device Type" "C402H22"
			(at 1.1811 -4.2291 270)
			(unlocked yes)
			(layer "F.Fab")
			(hide yes)
			(effects
				(font
					(size 1.016 1.016)
					(thickness 0.1524)
				)
			)
		)
		(duplicate_pad_numbers_are_jumpers no)
		(fp_rect
			(start -0.4318 0.9525)
			(end 0.4318 -0.9525)
			(stroke
				(width 0)
				(type default)
			)
			(fill no)
			(layer "F.CrtYd")
		)
		(fp_rect
			(start -0.4318 0.9525)
			(end 0.4318 -0.9525)
			(stroke
				(width 0)
				(type default)
			)
			(fill no)
			(layer "F.Fab")
		)
		(pad "1" smd custom
			(at 0 -0.4445 270)
			(size 0.1524 0.1524)
			(layers "F.Cu" "F.Mask" "F.Paste")
			(net "GND")
			(options
				(clearance outline)
				(anchor circle)
			)
			(primitives
				(gr_poly
					(pts
						(arc
							(start 0.3048 -0.2032)
							(mid 0.275042 -0.275042)
							(end 0.2032 -0.3048)
						)
						(arc
							(start -0.2032 -0.3048)
							(mid -0.275042 -0.275042)
							(end -0.3048 -0.2032)
						)
						(arc
							(start -0.3048 0.2032)
							(mid -0.275042 0.275042)
							(end -0.2032 0.3048)
						)
						(arc
							(start 0.2032 0.3048)
							(mid 0.275042 0.275042)
							(end 0.3048 0.2032)
						)
					)
					(width 0)
					(fill yes)
				)
			)
		)
		(pad "2" smd custom
			(at 0 0.4445 270)
			(size 0.1524 0.1524)
			(layers "F.Cu" "F.Mask" "F.Paste")
			(net "P3V3_STBY_B")
			(options
				(clearance outline)
				(anchor circle)
			)
			(primitives
				(gr_poly
					(pts
						(arc
							(start 0.3048 -0.2032)
							(mid 0.275042 -0.275042)
							(end 0.2032 -0.3048)
						)
						(arc
							(start -0.2032 -0.3048)
							(mid -0.275042 -0.275042)
							(end -0.3048 -0.2032)
						)
						(arc
							(start -0.3048 0.2032)
							(mid -0.275042 0.275042)
							(end -0.2032 0.3048)
						)
						(arc
							(start 0.2032 0.3048)
							(mid 0.275042 0.275042)
							(end 0.3048 0.2032)
						)
					)
					(width 0)
					(fill yes)
				)
			)
		)
	)
	(footprint ""
		(layer "F.Cu")
		(at 479.384614 -129.66065 -90)
		(property "Reference" "C328"
			(at 0 0 270)
			(layer "F.SilkS")
			(hide yes)
			(effects
				(font
					(size 1.27 1.27)
				)
			)
		)
		(property "Value" "SCD01U16V1KX-GP"
			(at -2.8321 -1.7399 270)
			(unlocked yes)
			(layer "F.Fab")
			(hide yes)
			(effects
				(font
					(size 1.016 1.016)
					(thickness 0.1524)
				)
			)
		)
		(property "Device Type" "C0201H13"
			(at -2.8321 -3.2639 270)
			(unlocked yes)
			(layer "F.Fab")
			(hide yes)
			(effects
				(font
					(size 1.016 1.016)
					(thickness 0.1524)
				)
			)
		)
		(duplicate_pad_numbers_are_jumpers no)
		(fp_rect
			(start -0.2794 0.6477)
			(end 0.2794 -0.6477)
			(stroke
				(width 0)
				(type default)
			)
			(fill no)
			(layer "F.CrtYd")
		)
		(fp_rect
			(start -0.2794 0.6477)
			(end 0.2794 -0.6477)
			(stroke
				(width 0)
				(type default)
			)
			(fill no)
			(layer "F.Fab")
		)
		(pad "1" smd custom
			(at 0 -0.2794 270)
			(size 0.0762 0.0762)
			(layers "F.Cu" "F.Mask" "F.Paste")
			(net "SAS_HDD_RX_P23")
			(options
				(clearance outline)
				(anchor circle)
			)
			(primitives
				(gr_poly
					(pts
						(arc
							(start 0.1524 -0.127)
							(mid 0.137521 -0.162921)
							(end 0.1016 -0.1778)
						)
						(arc
							(start -0.1016 -0.1778)
							(mid -0.137521 -0.162921)
							(end -0.1524 -0.127)
						)
						(arc
							(start -0.1524 0.127)
							(mid -0.137521 0.162921)
							(end -0.1016 0.1778)
						)
						(arc
							(start 0.1016 0.1778)
							(mid 0.137521 0.162921)
							(end 0.1524 0.127)
						)
					)
					(width 0)
					(fill yes)
				)
			)
		)
		(pad "2" smd custom
			(at 0 0.2794 270)
			(size 0.0762 0.0762)
			(layers "F.Cu" "F.Mask" "F.Paste")
			(net "PHY_SCC_B_TO_DRV_B_23_DP")
			(options
				(clearance outline)
				(anchor circle)
			)
			(primitives
				(gr_poly
					(pts
						(arc
							(start 0.1524 -0.127)
							(mid 0.137521 -0.162921)
							(end 0.1016 -0.1778)
						)
						(arc
							(start -0.1016 -0.1778)
							(mid -0.137521 -0.162921)
							(end -0.1524 -0.127)
						)
						(arc
							(start -0.1524 0.127)
							(mid -0.137521 0.162921)
							(end -0.1016 0.1778)
						)
						(arc
							(start 0.1016 0.1778)
							(mid 0.137521 0.162921)
							(end 0.1524 0.127)
						)
					)
					(width 0)
					(fill yes)
				)
			)
		)
	)
)
